# BASEBOARD_FAB2 (Tioga Pass) — schematic netlist excerpt (pin names and nets, part order shuffled) for the footprints in the layout excerpt that follows; sources: Cadence DE-HDL packaged netlist, KiCad conversion of Wiwynn_Tioga_Pass_MB.brd

U6W1  TCA9555PWR-GP  pkg DISCRET-GC1  page 247
  \int#\  = PCA9555_INT_N
  A1  = PCA9555_A1
  A2  = PCA9555_A2
  P00  = LED_POSTCODE_0_R
  P01  = LED_POSTCODE_1_R
  P02  = LED_POSTCODE_2_R
  P03  = LED_POSTCODE_3_R
  P04  = LED_POSTCODE_4_R
  P05  = LED_POSTCODE_5_R
  P06  = LED_POSTCODE_6_R
  P07  = LED_POSTCODE_7_R
  GND  = GND
  P10  = FM_DEBUG_RST_BTN_N
  P11  = FP_PWR_BTN_R_N
  P12  = PWRGD_SYS_PWROK
  P13  = RST_PLTRST_N
  P14  = PWRGD_DSW_PWROK
  P15  = FM_CPU_CATERR_MSMI_LVT3_N
  P16  = FM_SLPS3_N
  P17  = FM_UART_SWITCH_N
  A0  = PCA9555_A0
  SCL  = SMB_DEBUG_STBY_LVC3_SCL
  SDA  = SMB_DEBUG_STBY_LVC3_SDA
  VCC  = P3V3_STBY

(kicad_pcb
	(version 20260206)
	(generator "pcbnew")
	(generator_version "10.0")
	(general
		(thickness 1.6)
		(legacy_teardrops no)
	)
	(paper "A4")
	(title_block
		(title "Wiwynn_Tioga_Pass_MB.brd")
		(comment 1 "Tioga Pass / footprints 4661-4661 of 4770")
	)
	(layers
		(0 "F.Cu" signal "TOP")
		(4 "In1.Cu" signal "L2GND")
		(6 "In2.Cu" signal "L3")
		(8 "In3.Cu" signal "L4GND")
		(10 "In4.Cu" signal "L5")
		(12 "In5.Cu" signal "L6GND")
		(14 "In6.Cu" signal "L7VCC")
		(16 "In7.Cu" signal "L8VCC")
		(18 "In8.Cu" signal "L9GND")
		(20 "In9.Cu" signal "L10")
		(22 "In10.Cu" signal "L11GND")
		(24 "In11.Cu" signal "L12")
		(26 "In12.Cu" signal "L13GND")
		(2 "B.Cu" signal "BOTTOM")
		(9 "F.Adhes" user "F.Adhesive")
		(11 "B.Adhes" user "B.Adhesive")
		(13 "F.Paste" user "Package Geometry/Pastemask Top")
		(15 "B.Paste" user "Package Geometry/Pastemask Bottom")
		(5 "F.SilkS" user "Ref Des/Silkscreen Top")
		(7 "B.SilkS" user "Ref Des/Silkscreen Bottom")
		(1 "F.Mask" user "Board Geometry/Soldermask Top")
		(3 "B.Mask" user "Board Geometry/Soldermask Bottom")
		(17 "Dwgs.User" user "User.Drawings")
		(19 "Cmts.User" user "User.Comments")
		(21 "Eco1.User" user "User.Eco1")
		(23 "Eco2.User" user "User.Eco2")
		(25 "Edge.Cuts" user "Board Geometry/Outline")
		(27 "Margin" user)
		(31 "F.CrtYd" user "Package Geometry/Place Bound Top")
		(29 "B.CrtYd" user "Package Geometry/Place Bound Bottom")
		(35 "F.Fab" user "Ref Des/Assembly Top")
		(33 "B.Fab" user "Ref Des/Assembly Bottom")
	)
	(footprint ""
		(layer "B.Cu")
		(at 476.479616 -140.712952 90)
		(property "Reference" "U6W1"
			(at 0 0 90)
			(layer "B.SilkS")
			(hide yes)
			(effects
				(font
					(size 1.27 1.27)
				)
				(justify mirror)
			)
		)
		(property "Value" "*"
			(at 0 -7.0485 90)
			(unlocked yes)
			(layer "B.Fab")
			(hide yes)
			(effects
				(font
					(size 1.27 1.016)
					(thickness 0.1524)
				)
				(justify mirror)
			)
		)
		(property "Device Type" "TCA9555PWR-GP_DISCRET-GC1-TCA9A"
			(at 0 -8.6995 90)
			(unlocked yes)
			(layer "B.Fab")
			(hide yes)
			(effects
				(font
					(size 1.27 1.016)
					(thickness 0.1524)
				)
				(justify mirror)
			)
		)
		(duplicate_pad_numbers_are_jumpers no)
		(fp_line
			(start 4.2291 -1.397)
			(end -3.81 -1.397)
			(stroke
				(width 0.1524)
				(type default)
			)
			(layer "B.SilkS")
		)
		(fp_line
			(start -3.81 -1.397)
			(end -3.81 1.397)
			(stroke
				(width 0.1524)
				(type default)
			)
			(layer "B.SilkS")
		)
		(fp_line
			(start 4.2291 -0.8001)
			(end 3.429 0)
			(stroke
				(width 0.1524)
				(type default)
			)
			(layer "B.SilkS")
		)
		(fp_line
			(start 3.429 0)
			(end 4.2291 0.8001)
			(stroke
				(width 0.1524)
				(type default)
			)
			(layer "B.SilkS")
		)
		(fp_line
			(start -3.81 1.397)
			(end 4.2291 1.397)
			(stroke
				(width 0.1524)
				(type default)
			)
			(layer "B.SilkS")
		)
		(fp_line
			(start 4.22656 3.81)
			(end 4.2291 1.397)
			(stroke
				(width 0.508)
				(type default)
			)
			(layer "B.SilkS")
		)
		(fp_line
			(start 4.2291 3.937)
			(end 4.2291 -1.397)
			(stroke
				(width 0.1524)
				(type default)
			)
			(layer "B.SilkS")
		)
		(fp_poly
			(pts
				(xy 3.90652 -1.8542) (xy -3.90652 -1.8542) (xy -3.90652 1.8542) (xy 3.90652 1.8542)
			)
			(stroke
				(width 0)
				(type default)
			)
			(fill yes)
			(layer "B.SilkS")
		)
		(fp_poly
			(pts
				(xy 4.2164 3.81) (xy -4.2164 3.81) (xy -4.22656 -3.81) (xy 4.2164 -3.81)
			)
			(stroke
				(width 0)
				(type default)
			)
			(fill no)
			(layer "B.CrtYd")
		)
		(fp_poly
			(pts
				(xy 4.22656 -3.81) (xy -4.22656 -3.81) (xy -4.22656 3.81) (xy 4.22656 3.81)
			)
			(stroke
				(width 0)
				(type default)
			)
			(fill no)
			(layer "B.Fab")
		)
		(pad "1" smd rect
			(at 3.57632 2.8194 270)
			(size 0.3556 1.524)
			(layers "B.Cu" "B.Mask" "B.Paste")
			(net "PCA9555_INT_N")
		)
		(pad "2" smd rect
			(at 2.92608 2.8194 270)
			(size 0.3556 1.524)
			(layers "B.Cu" "B.Mask" "B.Paste")
			(net "PCA9555_A1")
		)
		(pad "3" smd rect
			(at 2.27584 2.8194 270)
			(size 0.3556 1.524)
			(layers "B.Cu" "B.Mask" "B.Paste")
			(net "PCA9555_A2")
		)
		(pad "4" smd rect
			(at 1.6256 2.8194 270)
			(size 0.3556 1.524)
			(layers "B.Cu" "B.Mask" "B.Paste")
			(net "LED_POSTCODE_0_R")
		)
		(pad "5" smd rect
			(at 0.97536 2.8194 270)
			(size 0.3556 1.524)
			(layers "B.Cu" "B.Mask" "B.Paste")
			(net "LED_POSTCODE_1_R")
		)
		(pad "6" smd rect
			(at 0.32512 2.8194 270)
			(size 0.3556 1.524)
			(layers "B.Cu" "B.Mask" "B.Paste")
			(net "LED_POSTCODE_2_R")
		)
		(pad "7" smd rect
			(at -0.32512 2.8194 270)
			(size 0.3556 1.524)
			(layers "B.Cu" "B.Mask" "B.Paste")
			(net "LED_POSTCODE_3_R")
		)
		(pad "8" smd rect
			(at -0.97536 2.8194 270)
			(size 0.3556 1.524)
			(layers "B.Cu" "B.Mask" "B.Paste")
			(net "LED_POSTCODE_4_R")
		)
		(pad "9" smd rect
			(at -1.6256 2.8194 270)
			(size 0.3556 1.524)
			(layers "B.Cu" "B.Mask" "B.Paste")
			(net "LED_POSTCODE_5_R")
		)
		(pad "10" smd rect
			(at -2.27584 2.8194 270)
			(size 0.3556 1.524)
			(layers "B.Cu" "B.Mask" "B.Paste")
			(net "LED_POSTCODE_6_R")
		)
		(pad "11" smd rect
			(at -2.92608 2.8194 270)
			(size 0.3556 1.524)
			(layers "B.Cu" "B.Mask" "B.Paste")
			(net "LED_POSTCODE_7_R")
		)
		(pad "12" smd rect
			(at -3.57632 2.8194 270)
			(size 0.3556 1.524)
			(layers "B.Cu" "B.Mask" "B.Paste")
			(net "GND")
		)
		(pad "13" smd rect
			(at -3.57632 -2.8194 270)
			(size 0.3556 1.524)
			(layers "B.Cu" "B.Mask" "B.Paste")
			(net "FM_DEBUG_RST_BTN_N")
		)
		(pad "14" smd rect
			(at -2.92608 -2.8194 270)
			(size 0.3556 1.524)
			(layers "B.Cu" "B.Mask" "B.Paste")
			(net "FP_PWR_BTN_R_N")
		)
		(pad "15" smd rect
			(at -2.27584 -2.8194 270)
			(size 0.3556 1.524)
			(layers "B.Cu" "B.Mask" "B.Paste")
			(net "PWRGD_SYS_PWROK")
		)
		(pad "16" smd rect
			(at -1.6256 -2.8194 270)
			(size 0.3556 1.524)
			(layers "B.Cu" "B.Mask" "B.Paste")
			(net "RST_PLTRST_N")
		)
		(pad "17" smd rect
			(at -0.97536 -2.8194 270)
			(size 0.3556 1.524)
			(layers "B.Cu" "B.Mask" "B.Paste")
			(net "PWRGD_DSW_PWROK")
		)
		(pad "18" smd rect
			(at -0.32512 -2.8194 270)
			(size 0.3556 1.524)
			(layers "B.Cu" "B.Mask" "B.Paste")
			(net "FM_CPU_CATERR_MSMI_LVT3_N")
		)
		(pad "19" smd rect
			(at 0.32512 -2.8194 270)
			(size 0.3556 1.524)
			(layers "B.Cu" "B.Mask" "B.Paste")
			(net "FM_SLPS3_N")
		)
		(pad "20" smd rect
			(at 0.97536 -2.8194 270)
			(size 0.3556 1.524)
			(layers "B.Cu" "B.Mask" "B.Paste")
			(net "FM_UART_SWITCH_N")
		)
		(pad "21" smd rect
			(at 1.6256 -2.8194 270)
			(size 0.3556 1.524)
			(layers "B.Cu" "B.Mask" "B.Paste")
			(net "PCA9555_A0")
		)
		(pad "22" smd rect
			(at 2.27584 -2.8194 270)
			(size 0.3556 1.524)
			(layers "B.Cu" "B.Mask" "B.Paste")
			(net "SMB_DEBUG_STBY_LVC3_SCL")
		)
		(pad "23" smd rect
			(at 2.92608 -2.8194 270)
			(size 0.3556 1.524)
			(layers "B.Cu" "B.Mask" "B.Paste")
			(net "SMB_DEBUG_STBY_LVC3_SDA")
		)
		(pad "24" smd rect
			(at 3.57632 -2.8194 270)
			(size 0.3556 1.524)
			(layers "B.Cu" "B.Mask" "B.Paste")
			(net "P3V3_STBY")
		)
	)
)
